# S9S_MB_2U (Grand Teton) — schematic netlist excerpt (pin names and nets, part order shuffled) for the footprints in the layout excerpt that follows; sources: Cadence DE-HDL packaged netlist, KiCad conversion of 03242023_DA0F0TMBIJ0_F0T_Motherboard_J_brd_V01_OCP.brd

PC1179_P0_3  Q_CAP  22UF 16V 20% X6S  pkg C0805  page 272 : A = SW_P12V_PVCCFA_EHV_FIVRA_CPU0_R ; B = GND
R595  Q_RES  0 5% CHIP  pkg 0402LF  page 241 : A = I3C_SPD_DDREFGH_CPU0_BMC_R_SCL ; B = I3C_SPD_DDREFGH_CPU0_BMC_SCL
R1764  Q_RES  1K 1% EMPTY  pkg 0402LF  page 257 : A = FM_LPC_ESPI_SEL ; B = GND

(kicad_pcb
	(version 20260206)
	(generator "pcbnew")
	(generator_version "10.0")
	(general
		(thickness 1.6)
		(legacy_teardrops no)
	)
	(paper "A4")
	(title_block
		(title "03242023_DA0F0TMBIJ0_F0T_Motherboard_J_brd_V01_OCP.brd")
		(comment 1 "Grand Teton / footprints 5401-5403 of 6105")
	)
	(layers
		(0 "F.Cu" signal "TOP")
		(4 "In1.Cu" signal "GND")
		(6 "In2.Cu" signal "IN1")
		(8 "In3.Cu" signal "GND1")
		(10 "In4.Cu" signal "IN2")
		(12 "In5.Cu" signal "GND2")
		(14 "In6.Cu" signal "IN3")
		(16 "In7.Cu" signal "GND3")
		(18 "In8.Cu" signal "VCC")
		(20 "In9.Cu" signal "VCC1")
		(22 "In10.Cu" signal "GND4")
		(24 "In11.Cu" signal "IN4")
		(26 "In12.Cu" signal "GND5")
		(28 "In13.Cu" signal "IN5")
		(30 "In14.Cu" signal "GND6")
		(32 "In15.Cu" signal "IN6")
		(34 "In16.Cu" signal "GND7")
		(2 "B.Cu" signal "BOTTOM")
		(9 "F.Adhes" user "F.Adhesive")
		(11 "B.Adhes" user "B.Adhesive")
		(13 "F.Paste" user "Package Geometry/Pastemask Top")
		(15 "B.Paste" user "Package Geometry/Pastemask Bottom")
		(5 "F.SilkS" user "Ref Des/Silkscreen Top")
		(7 "B.SilkS" user "Ref Des/Silkscreen Bottom")
		(1 "F.Mask" user "Board Geometry/Soldermask Top")
		(3 "B.Mask" user "Board Geometry/Soldermask Bottom")
		(17 "Dwgs.User" user "User.Drawings")
		(19 "Cmts.User" user "User.Comments")
		(21 "Eco1.User" user "User.Eco1")
		(23 "Eco2.User" user "User.Eco2")
		(25 "Edge.Cuts" user "Board Geometry/Outline")
		(27 "Margin" user)
		(31 "F.CrtYd" user "Package Geometry/Place Bound Top")
		(29 "B.CrtYd" user "Package Geometry/Place Bound Bottom")
		(35 "F.Fab" user "Ref Des/Assembly Top")
		(33 "B.Fab" user "Ref Des/Assembly Bottom")
	)
	(footprint ""
		(layer "B.Cu")
		(at 174.393352 -22.564598 -90)
		(property "Reference" "R1764"
			(at 0 0 90)
			(layer "B.SilkS")
			(hide yes)
			(effects
				(font
					(size 1.27 1.27)
				)
				(justify mirror)
			)
		)
		(property "Value" ""
			(at 0 0 90)
			(layer "B.Fab")
			(effects
				(font
					(size 1.27 1.27)
				)
				(justify mirror)
			)
		)
		(duplicate_pad_numbers_are_jumpers no)
		(fp_line
			(start -0.7874 0.4064)
			(end 0.7874 0.4064)
			(stroke
				(width 0.1524)
				(type default)
			)
			(layer "B.SilkS")
		)
		(fp_line
			(start 0.7874 0.4064)
			(end 0.7874 -0.4064)
			(stroke
				(width 0.1524)
				(type default)
			)
			(layer "B.SilkS")
		)
		(fp_line
			(start -0.7874 -0.4064)
			(end -0.7874 0.4064)
			(stroke
				(width 0.1524)
				(type default)
			)
			(layer "B.SilkS")
		)
		(fp_line
			(start 0.7874 -0.4064)
			(end -0.7874 -0.4064)
			(stroke
				(width 0.1524)
				(type default)
			)
			(layer "B.SilkS")
		)
		(fp_line
			(start -0.67945 0.3048)
			(end -0.120396 0.3048)
			(stroke
				(width 0.1)
				(type default)
			)
			(layer "B.Fab")
		)
		(fp_line
			(start -0.120396 0.3048)
			(end -0.120396 0.2794)
			(stroke
				(width 0.1)
				(type default)
			)
			(layer "B.Fab")
		)
		(fp_line
			(start 0.12065 0.3048)
			(end 0.67945 0.3048)
			(stroke
				(width 0.1)
				(type default)
			)
			(layer "B.Fab")
		)
		(fp_line
			(start 0.67945 0.3048)
			(end 0.67945 -0.305054)
			(stroke
				(width 0.1)
				(type default)
			)
			(layer "B.Fab")
		)
		(fp_line
			(start -0.120396 0.2794)
			(end 0.12065 0.2794)
			(stroke
				(width 0.1)
				(type default)
			)
			(layer "B.Fab")
		)
		(fp_line
			(start 0.12065 0.2794)
			(end 0.12065 0.3048)
			(stroke
				(width 0.1)
				(type default)
			)
			(layer "B.Fab")
		)
		(fp_line
			(start -0.12065 -0.2794)
			(end -0.12065 -0.3048)
			(stroke
				(width 0.1)
				(type default)
			)
			(layer "B.Fab")
		)
		(fp_line
			(start 0.12065 -0.2794)
			(end -0.12065 -0.2794)
			(stroke
				(width 0.1)
				(type default)
			)
			(layer "B.Fab")
		)
		(fp_line
			(start -0.67945 -0.3048)
			(end -0.67945 0.3048)
			(stroke
				(width 0.1)
				(type default)
			)
			(layer "B.Fab")
		)
		(fp_line
			(start -0.12065 -0.3048)
			(end -0.67945 -0.3048)
			(stroke
				(width 0.1)
				(type default)
			)
			(layer "B.Fab")
		)
		(fp_line
			(start 0.12065 -0.305054)
			(end 0.12065 -0.2794)
			(stroke
				(width 0.1)
				(type default)
			)
			(layer "B.Fab")
		)
		(fp_line
			(start 0.67945 -0.305054)
			(end 0.12065 -0.305054)
			(stroke
				(width 0.1)
				(type default)
			)
			(layer "B.Fab")
		)
		(pad "1" smd circle
			(at 0.40005 0 90)
			(size 0 0)
			(layers "B.Cu" "B.Mask" "B.Paste")
			(net "FM_LPC_ESPI_SEL")
		)
		(pad "2" smd circle
			(at -0.40005 0 90)
			(size 0 0)
			(layers "B.Cu" "B.Mask" "B.Paste")
			(net "GND")
		)
	)
	(footprint ""
		(layer "B.Cu")
		(at 188.309758 -13.60043 -90)
		(property "Reference" "R595"
			(at 0 0 90)
			(layer "B.SilkS")
			(hide yes)
			(effects
				(font
					(size 1.27 1.27)
				)
				(justify mirror)
			)
		)
		(property "Value" ""
			(at 0 0 90)
			(layer "B.Fab")
			(effects
				(font
					(size 1.27 1.27)
				)
				(justify mirror)
			)
		)
		(duplicate_pad_numbers_are_jumpers no)
		(fp_line
			(start -0.7874 0.4064)
			(end 0.7874 0.4064)
			(stroke
				(width 0.1524)
				(type default)
			)
			(layer "B.SilkS")
		)
		(fp_line
			(start 0.7874 0.4064)
			(end 0.7874 -0.4064)
			(stroke
				(width 0.1524)
				(type default)
			)
			(layer "B.SilkS")
		)
		(fp_line
			(start -0.7874 -0.4064)
			(end -0.7874 0.4064)
			(stroke
				(width 0.1524)
				(type default)
			)
			(layer "B.SilkS")
		)
		(fp_line
			(start 0.7874 -0.4064)
			(end -0.7874 -0.4064)
			(stroke
				(width 0.1524)
				(type default)
			)
			(layer "B.SilkS")
		)
		(fp_line
			(start -0.67945 0.3048)
			(end -0.120396 0.3048)
			(stroke
				(width 0.1)
				(type default)
			)
			(layer "B.Fab")
		)
		(fp_line
			(start -0.120396 0.3048)
			(end -0.120396 0.2794)
			(stroke
				(width 0.1)
				(type default)
			)
			(layer "B.Fab")
		)
		(fp_line
			(start 0.12065 0.3048)
			(end 0.67945 0.3048)
			(stroke
				(width 0.1)
				(type default)
			)
			(layer "B.Fab")
		)
		(fp_line
			(start 0.67945 0.3048)
			(end 0.67945 -0.305054)
			(stroke
				(width 0.1)
				(type default)
			)
			(layer "B.Fab")
		)
		(fp_line
			(start -0.120396 0.2794)
			(end 0.12065 0.2794)
			(stroke
				(width 0.1)
				(type default)
			)
			(layer "B.Fab")
		)
		(fp_line
			(start 0.12065 0.2794)
			(end 0.12065 0.3048)
			(stroke
				(width 0.1)
				(type default)
			)
			(layer "B.Fab")
		)
		(fp_line
			(start -0.12065 -0.2794)
			(end -0.12065 -0.3048)
			(stroke
				(width 0.1)
				(type default)
			)
			(layer "B.Fab")
		)
		(fp_line
			(start 0.12065 -0.2794)
			(end -0.12065 -0.2794)
			(stroke
				(width 0.1)
				(type default)
			)
			(layer "B.Fab")
		)
		(fp_line
			(start -0.67945 -0.3048)
			(end -0.67945 0.3048)
			(stroke
				(width 0.1)
				(type default)
			)
			(layer "B.Fab")
		)
		(fp_line
			(start -0.12065 -0.3048)
			(end -0.67945 -0.3048)
			(stroke
				(width 0.1)
				(type default)
			)
			(layer "B.Fab")
		)
		(fp_line
			(start 0.12065 -0.305054)
			(end 0.12065 -0.2794)
			(stroke
				(width 0.1)
				(type default)
			)
			(layer "B.Fab")
		)
		(fp_line
			(start 0.67945 -0.305054)
			(end 0.12065 -0.305054)
			(stroke
				(width 0.1)
				(type default)
			)
			(layer "B.Fab")
		)
		(pad "1" smd circle
			(at 0.40005 0 90)
			(size 0 0)
			(layers "B.Cu" "B.Mask" "B.Paste")
			(net "I3C_SPD_DDREFGH_CPU0_BMC_R_SCL")
		)
		(pad "2" smd circle
			(at -0.40005 0 90)
			(size 0 0)
			(layers "B.Cu" "B.Mask" "B.Paste")
			(net "I3C_SPD_DDREFGH_CPU0_BMC_SCL")
		)
	)
	(footprint ""
		(layer "B.Cu")
		(at 429.105568 -362.107226 90)
		(property "Reference" "PC1179_P0_3"
			(at 0 0 90)
			(layer "B.SilkS")
			(hide yes)
			(effects
				(font
					(size 1.27 1.27)
				)
				(justify mirror)
			)
		)
		(property "Value" ""
			(at 0 0 90)
			(layer "B.Fab")
			(effects
				(font
					(size 1.27 1.27)
				)
				(justify mirror)
			)
		)
		(duplicate_pad_numbers_are_jumpers no)
		(fp_line
			(start 1.524 -0.762)
			(end -1.524 -0.762)
			(stroke
				(width 0.1524)
				(type default)
			)
			(layer "B.SilkS")
		)
		(fp_line
			(start -1.524 -0.762)
			(end -1.524 0.762)
			(stroke
				(width 0.1524)
				(type default)
			)
			(layer "B.SilkS")
		)
		(fp_line
			(start 1.524 0.762)
			(end 1.524 -0.762)
			(stroke
				(width 0.1524)
				(type default)
			)
			(layer "B.SilkS")
		)
		(fp_line
			(start -1.524 0.762)
			(end 1.524 0.762)
			(stroke
				(width 0.1524)
				(type default)
			)
			(layer "B.SilkS")
		)
		(fp_line
			(start 1.1049 -0.724916)
			(end 1.1049 0.724916)
			(stroke
				(width 0.1)
				(type default)
			)
			(layer "B.Fab")
		)
		(fp_line
			(start -1.1049 -0.724916)
			(end 1.1049 -0.724916)
			(stroke
				(width 0.1)
				(type default)
			)
			(layer "B.Fab")
		)
		(fp_line
			(start 1.1049 0.724916)
			(end -1.1049 0.724916)
			(stroke
				(width 0.1)
				(type default)
			)
			(layer "B.Fab")
		)
		(fp_line
			(start -1.1049 0.724916)
			(end -1.1049 -0.724916)
			(stroke
				(width 0.1)
				(type default)
			)
			(layer "B.Fab")
		)
		(pad "1" smd rect
			(at 0.889 0 90)
			(size 1.016 1.27)
			(layers "B.Cu" "B.Mask" "B.Paste")
			(net "SW_P12V_PVCCFA_EHV_FIVRA_CPU0_R")
		)
		(pad "2" smd rect
			(at -0.889 0 90)
			(size 1.016 1.27)
			(layers "B.Cu" "B.Mask" "B.Paste")
			(net "GND")
		)
	)
)
